(kicad_pcb
	(version 20241229)
	(generator "pcbnew")
	(generator_version "9.0")
	(general
		(thickness 1.6)
		(legacy_teardrops no)
	)
	(paper "A4")
	(title_block
		(title "environment-sensor")
		(comment 1 "footprints 100-105 of 109")
	)
	(layers
		(0 "F.Cu" signal)
		(4 "In1.Cu" signal)
		(6 "In2.Cu" signal)
		(2 "B.Cu" signal)
		(9 "F.Adhes" user "F.Adhesive")
		(11 "B.Adhes" user "B.Adhesive")
		(13 "F.Paste" user)
		(15 "B.Paste" user)
		(5 "F.SilkS" user "F.Silkscreen")
		(7 "B.SilkS" user "B.Silkscreen")
		(1 "F.Mask" user)
		(3 "B.Mask" user)
		(17 "Dwgs.User" user "User.Drawings")
		(19 "Cmts.User" user "User.Comments")
		(21 "Eco1.User" user "User.Eco1")
		(23 "Eco2.User" user "User.Eco2")
		(25 "Edge.Cuts" user)
		(27 "Margin" user)
		(31 "F.CrtYd" user "F.Courtyard")
		(29 "B.CrtYd" user "B.Courtyard")
		(35 "F.Fab" user)
		(33 "B.Fab" user)
	)
	(footprint "antmicro-footprints:R_0402_1005Metric"
		(layer "F.Cu")
		(at 190.444 125.087 90)
		(descr "Resistor SMD 0402")
		(tags "resistor SMD 0402")
		(property "Reference" "R27"
			(at 3.887 4.656 0)
			(layer "F.SilkS")
			(effects
				(font
					(size 0.7 0.7)
					(thickness 0.15)
				)
				(justify left bottom)
			)
		)
		(property "Value" "R_100R_0402"
			(at 0 1.4 90)
			(layer "F.Fab")
			(effects
				(font
					(size 0.7 0.7)
					(thickness 0.15)
				)
				(justify left bottom)
			)
		)
		(property "Description" "SMD Chip Resistor, 100 ohm, ± 1%, 62.5 mW, 0402 [1005 Metric], Thick Film, General Purpose"
			(at 0 0 90)
			(layer "F.Fab")
			(hide yes)
			(effects
				(font
					(size 1.27 1.27)
					(thickness 0.15)
				)
			)
		)
		(property "Author" "Antmicro"
			(at 315.531 -65.357 0)
			(layer "F.Fab")
			(hide yes)
			(effects
				(font
					(size 1 1)
					(thickness 0.15)
				)
			)
		)
		(property "License" "Apache-2.0"
			(at 315.531 -65.357 0)
			(layer "F.Fab")
			(hide yes)
			(effects
				(font
					(size 1 1)
					(thickness 0.15)
				)
			)
		)
		(property "MPN" "CR0402-FX-1000GLF"
			(at 315.531 -65.357 0)
			(layer "F.Fab")
			(hide yes)
			(effects
				(font
					(size 1 1)
					(thickness 0.15)
				)
			)
		)
		(property "Manufacturer" "Bourns"
			(at 315.531 -65.357 0)
			(layer "F.Fab")
			(hide yes)
			(effects
				(font
					(size 1 1)
					(thickness 0.15)
				)
			)
		)
		(property "Public" "False"
			(at 315.531 -65.357 0)
			(layer "F.Fab")
			(hide yes)
			(effects
				(font
					(size 1 1)
					(thickness 0.15)
				)
			)
		)
		(property "Tolerance" "1%"
			(at 315.531 -65.357 0)
			(layer "F.Fab")
			(hide yes)
			(effects
				(font
					(size 1 1)
					(thickness 0.15)
				)
			)
		)
		(property "Val" "100R"
			(at 315.531 -65.357 0)
			(layer "F.Fab")
			(hide yes)
			(effects
				(font
					(size 1 1)
					(thickness 0.15)
				)
			)
		)
		(sheetfile "environment-sensor.kicad_sch")
		(attr smd)
		(fp_rect
			(start -0.925 -0.47)
			(end 0.925 0.47)
			(stroke
				(width 0.05)
				(type default)
			)
			(fill no)
			(layer "F.CrtYd")
		)
		(fp_rect
			(start -0.5 -0.25)
			(end 0.5 0.25)
			(stroke
				(width 0.15)
				(type solid)
			)
			(fill no)
			(layer "F.Fab")
		)
		(pad "1" smd roundrect
			(at -0.48 0 90)
			(size 0.59 0.64)
			(layers "F.Cu" "F.Mask" "F.Paste")
			(roundrect_rratio 0.25)
			(net 49 "Net-(U3-PB8-BOOT0)")
			(pintype "passive")
		)
		(pad "2" smd roundrect
			(at 0.48 0 90)
			(size 0.59 0.64)
			(layers "F.Cu" "F.Mask" "F.Paste")
			(roundrect_rratio 0.25)
			(net 8 "I2C_1_SCL")
			(pintype "passive")
		)
	)
	(footprint "antmicro-footprints:R_0402_1005Metric"
		(layer "F.Cu")
		(at 198.5 132.5)
		(descr "Resistor SMD 0402")
		(tags "resistor SMD 0402")
		(property "Reference" "R21"
			(at 0.85 0.4 0)
			(layer "F.SilkS")
			(effects
				(font
					(size 0.7 0.7)
					(thickness 0.15)
				)
				(justify left bottom)
			)
		)
		(property "Value" "R_100R_0402"
			(at -1.011843 1.772047 0)
			(layer "F.Fab")
			(effects
				(font
					(size 0.7 0.7)
					(thickness 0.15)
				)
				(justify left bottom)
			)
		)
		(property "Description" "SMD Chip Resistor, 100 ohm, ± 1%, 62.5 mW, 0402 [1005 Metric], Thick Film, General Purpose"
			(at 0 0 0)
			(layer "F.Fab")
			(hide yes)
			(effects
				(font
					(size 1.27 1.27)
					(thickness 0.15)
				)
			)
		)
		(property "Author" "Antmicro"
			(at 0 0 0)
			(layer "F.Fab")
			(hide yes)
			(effects
				(font
					(size 1 1)
					(thickness 0.15)
				)
			)
		)
		(property "License" "Apache-2.0"
			(at 0 0 0)
			(layer "F.Fab")
			(hide yes)
			(effects
				(font
					(size 1 1)
					(thickness 0.15)
				)
			)
		)
		(property "MPN" "CR0402-FX-1000GLF"
			(at 0 0 0)
			(layer "F.Fab")
			(hide yes)
			(effects
				(font
					(size 1 1)
					(thickness 0.15)
				)
			)
		)
		(property "Manufacturer" "Bourns"
			(at 0 0 0)
			(layer "F.Fab")
			(hide yes)
			(effects
				(font
					(size 1 1)
					(thickness 0.15)
				)
			)
		)
		(property "Public" "False"
			(at 0 0 0)
			(layer "F.Fab")
			(hide yes)
			(effects
				(font
					(size 1 1)
					(thickness 0.15)
				)
			)
		)
		(property "Tolerance" "1%"
			(at 0 0 0)
			(layer "F.Fab")
			(hide yes)
			(effects
				(font
					(size 1 1)
					(thickness 0.15)
				)
			)
		)
		(property "Val" "100R"
			(at 0 0 0)
			(layer "F.Fab")
			(hide yes)
			(effects
				(font
					(size 1 1)
					(thickness 0.15)
				)
			)
		)
		(sheetfile "environment-sensor.kicad_sch")
		(attr smd exclude_from_pos_files exclude_from_bom dnp)
		(fp_rect
			(start -0.925 -0.47)
			(end 0.925 0.47)
			(stroke
				(width 0.05)
				(type default)
			)
			(fill no)
			(layer "F.CrtYd")
		)
		(fp_rect
			(start -0.5 -0.25)
			(end 0.5 0.25)
			(stroke
				(width 0.15)
				(type solid)
			)
			(fill no)
			(layer "F.Fab")
		)
		(pad "1" smd roundrect
			(at -0.48 0)
			(size 0.59 0.64)
			(layers "F.Cu" "F.Mask" "F.Paste")
			(roundrect_rratio 0.25)
			(net 47 "Net-(U3-PA8)")
			(pintype "passive")
		)
		(pad "2" smd roundrect
			(at 0.48 0)
			(size 0.59 0.64)
			(layers "F.Cu" "F.Mask" "F.Paste")
			(roundrect_rratio 0.25)
			(net 9 "I2C_1_SDA")
			(pintype "passive")
		)
	)
	(footprint "antmicro-footprints:R_0402_1005Metric"
		(layer "F.Cu")
		(at 184.75 126.25 -90)
		(descr "Resistor SMD 0402")
		(tags "resistor SMD 0402")
		(property "Reference" "R9"
			(at -10.25 -0.95 90)
			(layer "B.SilkS")
			(effects
				(font
					(size 0.7 0.7)
					(thickness 0.15)
				)
				(justify right bottom mirror)
			)
		)
		(property "Value" "R_0R_0402"
			(at 0 1.4 90)
			(layer "F.Fab")
			(effects
				(font
					(size 0.7 0.7)
					(thickness 0.15)
				)
				(justify right bottom)
			)
		)
		(property "Description" "SMD Chip Resistor, Jumper, 0 ohm, 100 mW, 0402 [1005 Metric], Thick Film, General Purpose"
			(at 0 0 270)
			(layer "F.Fab")
			(hide yes)
			(effects
				(font
					(size 1.27 1.27)
					(thickness 0.15)
				)
			)
		)
		(property "Author" "Antmicro"
			(at 58.5 311 0)
			(layer "F.Fab")
			(hide yes)
			(effects
				(font
					(size 1 1)
					(thickness 0.15)
				)
			)
		)
		(property "Current" "1A"
			(at 58.5 311 0)
			(layer "F.Fab")
			(hide yes)
			(effects
				(font
					(size 1 1)
					(thickness 0.15)
				)
			)
		)
		(property "License" "Apache-2.0"
			(at 58.5 311 0)
			(layer "F.Fab")
			(hide yes)
			(effects
				(font
					(size 1 1)
					(thickness 0.15)
				)
			)
		)
		(property "MPN" "ERJ2GE0R00X"
			(at 58.5 311 0)
			(layer "F.Fab")
			(hide yes)
			(effects
				(font
					(size 1 1)
					(thickness 0.15)
				)
			)
		)
		(property "Manufacturer" "Panasonic"
			(at 58.5 311 0)
			(layer "F.Fab")
			(hide yes)
			(effects
				(font
					(size 1 1)
					(thickness 0.15)
				)
			)
		)
		(property "Public" "False"
			(at 58.5 311 0)
			(layer "F.Fab")
			(hide yes)
			(effects
				(font
					(size 1 1)
					(thickness 0.15)
				)
			)
		)
		(property "Tolerance" ""
			(at 58.5 311 0)
			(layer "F.Fab")
			(hide yes)
			(effects
				(font
					(size 1 1)
					(thickness 0.15)
				)
			)
		)
		(property "Val" "0R"
			(at 58.5 311 0)
			(layer "F.Fab")
			(hide yes)
			(effects
				(font
					(size 1 1)
					(thickness 0.15)
				)
			)
		)
		(sheetfile "environment-sensor.kicad_sch")
		(attr smd)
		(fp_rect
			(start -0.925 -0.47)
			(end 0.925 0.47)
			(stroke
				(width 0.05)
				(type default)
			)
			(fill no)
			(layer "F.CrtYd")
		)
		(fp_rect
			(start -0.5 -0.25)
			(end 0.5 0.25)
			(stroke
				(width 0.15)
				(type solid)
			)
			(fill no)
			(layer "F.Fab")
		)
		(pad "1" smd roundrect
			(at -0.48 0 270)
			(size 0.59 0.64)
			(layers "F.Cu" "F.Mask" "F.Paste")
			(roundrect_rratio 0.25)
			(net 41 "Net-(U1-CTS#)")
			(pintype "passive")
		)
		(pad "2" smd roundrect
			(at 0.48 0 270)
			(size 0.59 0.64)
			(layers "F.Cu" "F.Mask" "F.Paste")
			(roundrect_rratio 0.25)
			(net 19 "JTDO")
			(pintype "passive")
		)
	)
	(footprint "antmicro-footprints:LED_0603_1608Metric_G"
		(layer "F.Cu")
		(at 175.1 138.7)
		(descr "LED SMD 0603 Green")
		(tags "LED SMD 0603 Green")
		(property "Reference" "LD2"
			(at 25.7 0.9 0)
			(layer "F.SilkS")
			(effects
				(font
					(size 0.7 0.7)
					(thickness 0.15)
				)
				(justify left bottom)
			)
		)
		(property "Value" "LED_G_0603_KP-1608ZGC"
			(at 0 1.6 0)
			(layer "F.Fab")
			(effects
				(font
					(size 0.7 0.7)
					(thickness 0.15)
				)
				(justify left bottom)
			)
		)
		(property "Description" "LED, Green, SMD, 0603, 20 mA, 3.3 V, 525 nm"
			(at 0 0 0)
			(layer "F.Fab")
			(hide yes)
			(effects
				(font
					(size 1.27 1.27)
					(thickness 0.15)
				)
			)
		)
		(property "Author" "Antmicro"
			(at 0 0 0)
			(layer "F.Fab")
			(hide yes)
			(effects
				(font
					(size 1 1)
					(thickness 0.15)
				)
			)
		)
		(property "Color" "Green"
			(at 0 0 0)
			(layer "F.Fab")
			(hide yes)
			(effects
				(font
					(size 1 1)
					(thickness 0.15)
				)
			)
		)
		(property "License" "Apache-2.0"
			(at 0 0 0)
			(layer "F.Fab")
			(hide yes)
			(effects
				(font
					(size 1 1)
					(thickness 0.15)
				)
			)
		)
		(property "MPN" "KP-1608ZGC"
			(at 0 0 0)
			(layer "F.Fab")
			(hide yes)
			(effects
				(font
					(size 1 1)
					(thickness 0.15)
				)
			)
		)
		(property "Manufacturer" "Kingbright"
			(at 0 0 0)
			(layer "F.Fab")
			(hide yes)
			(effects
				(font
					(size 1 1)
					(thickness 0.15)
				)
			)
		)
		(property "Public" "False"
			(at 0 0 0)
			(layer "F.Fab")
			(hide yes)
			(effects
				(font
					(size 1 1)
					(thickness 0.15)
				)
			)
		)
		(sheetfile "environment-sensor.kicad_sch")
		(attr smd)
		(fp_line
			(start -1.18 -0.319)
			(end -1.18 0.321)
			(stroke
				(width 0.15)
				(type solid)
			)
			(layer "F.SilkS")
		)
		(fp_line
			(start -0.094672 0.001008)
			(end -0.24 0.001008)
			(stroke
				(width 0.1)
				(type solid)
			)
			(layer "F.SilkS")
		)
		(fp_line
			(start -0.094672 0.001008)
			(end 0.105328 -0.198992)
			(stroke
				(width 0.1)
				(type solid)
			)
			(layer "F.SilkS")
		)
		(fp_line
			(start -0.094672 0.201008)
			(end -0.094672 -0.198992)
			(stroke
				(width 0.1)
				(type solid)
			)
			(layer "F.SilkS")
		)
		(fp_line
			(start 0.105328 0.001008)
			(end 0.24 0.001)
			(stroke
				(width 0.1)
				(type solid)
			)
			(layer "F.SilkS")
		)
		(fp_line
			(start 0.105328 0.201008)
			(end -0.094672 0.001008)
			(stroke
				(width 0.1)
				(type solid)
			)
			(layer "F.SilkS")
		)
		(fp_line
			(start 0.105328 0.201008)
			(end 0.105328 -0.198992)
			(stroke
				(width 0.1)
				(type solid)
			)
			(layer "F.SilkS")
		)
		(fp_line
			(start 0.22 -0.35)
			(end -0.22 -0.35)
			(stroke
				(width 0.15)
				(type solid)
			)
			(layer "F.SilkS")
		)
		(fp_line
			(start 0.22 0.35)
			(end -0.22 0.35)
			(stroke
				(width 0.15)
				(type solid)
			)
			(layer "F.SilkS")
		)
		(fp_rect
			(start 1.25 0.65)
			(end -1.25 -0.65)
			(stroke
				(width 0.05)
				(type solid)
			)
			(fill no)
			(layer "F.CrtYd")
		)
		(fp_line
			(start -0.199 -0.202)
			(end -0.199 0.1)
			(stroke
				(width 0.15)
				(type solid)
			)
			(layer "F.Fab")
		)
		(fp_line
			(start -0.199 0)
			(end -0.597 0)
			(stroke
				(width 0.15)
				(type solid)
			)
			(layer "F.Fab")
		)
		(fp_line
			(start -0.199 0.2)
			(end -0.199 0.1)
			(stroke
				(width 0.15)
				(type solid)
			)
			(layer "F.Fab")
		)
		(fp_line
			(start -0.101 0)
			(end 0.201 0.2)
			(stroke
				(width 0.15)
				(type solid)
			)
			(layer "F.Fab")
		)
		(fp_line
			(start 0.201 -0.202)
			(end -0.101 0)
			(stroke
				(width 0.15)
				(type solid)
			)
			(layer "F.Fab")
		)
		(fp_line
			(start 0.201 0)
			(end 0.201 -0.202)
			(stroke
				(width 0.15)
				(type solid)
			)
			(layer "F.Fab")
		)
		(fp_line
			(start 0.201 0.2)
			(end 0.201 0)
			(stroke
				(width 0.15)
				(type solid)
			)
			(layer "F.Fab")
		)
		(fp_line
			(start 0.599 0)
			(end 0.201 0)
			(stroke
				(width 0.15)
				(type solid)
			)
			(layer "F.Fab")
		)
		(fp_rect
			(start 0.848 0.4)
			(end -0.85 -0.402)
			(stroke
				(width 0.15)
				(type solid)
			)
			(fill no)
			(layer "F.Fab")
		)
		(pad "1" smd roundrect
			(at -0.7 0 180)
			(size 0.8 1)
			(layers "F.Cu" "F.Mask" "F.Paste")
			(roundrect_rratio 0.2)
			(net 12 "/LD2")
			(pinfunction "C")
			(pintype "passive")
		)
		(pad "2" smd roundrect
			(at 0.7 0 180)
			(size 0.8 1)
			(layers "F.Cu" "F.Mask" "F.Paste")
			(roundrect_rratio 0.2)
			(net 11 "Net-(LD2-A)")
			(pinfunction "A")
			(pintype "passive")
		)
	)
	(footprint "antmicro-footprints:C_0402_1005Metric"
		(layer "F.Cu")
		(at 205.15 115.835 90)
		(descr "Capacitor SMD 0402")
		(tags "capacitor SMD 0402")
		(property "Reference" "C27"
			(at -5.461 -2.977 180)
			(layer "F.SilkS")
			(effects
				(font
					(size 0.7 0.7)
					(thickness 0.15)
				)
				(justify left bottom)
			)
		)
		(property "Value" "C_100n_0402"
			(at 0 1.4 90)
			(layer "F.Fab")
			(effects
				(font
					(size 0.7 0.7)
					(thickness 0.15)
				)
				(justify left bottom)
			)
		)
		(property "Description" "SMD Multilayer Ceramic Capacitor, 0.1 µF, 50 V, 0402 [1005 Metric], ± 10%, X5R, GRM Series"
			(at 0 0 90)
			(layer "F.Fab")
			(hide yes)
			(effects
				(font
					(size 1.27 1.27)
					(thickness 0.15)
				)
			)
		)
		(property "Author" "Antmicro"
			(at 320.985 -89.315 0)
			(layer "F.Fab")
			(hide yes)
			(effects
				(font
					(size 1 1)
					(thickness 0.15)
				)
			)
		)
		(property "Dielectric" "X5R"
			(at 320.985 -89.315 0)
			(layer "F.Fab")
			(hide yes)
			(effects
				(font
					(size 1 1)
					(thickness 0.15)
				)
			)
		)
		(property "License" "Apache-2.0"
			(at 320.985 -89.315 0)
			(layer "F.Fab")
			(hide yes)
			(effects
				(font
					(size 1 1)
					(thickness 0.15)
				)
			)
		)
		(property "MPN" "GRM155R61H104KE14D"
			(at 320.985 -89.315 0)
			(layer "F.Fab")
			(hide yes)
			(effects
				(font
					(size 1 1)
					(thickness 0.15)
				)
			)
		)
		(property "Manufacturer" "Murata"
			(at 320.985 -89.315 0)
			(layer "F.Fab")
			(hide yes)
			(effects
				(font
					(size 1 1)
					(thickness 0.15)
				)
			)
		)
		(property "Public" "False"
			(at 320.985 -89.315 0)
			(layer "F.Fab")
			(hide yes)
			(effects
				(font
					(size 1 1)
					(thickness 0.15)
				)
			)
		)
		(property "Val" "100n"
			(at 320.985 -89.315 0)
			(layer "F.Fab")
			(hide yes)
			(effects
				(font
					(size 1 1)
					(thickness 0.15)
				)
			)
		)
		(property "Voltage" "50V"
			(at 320.985 -89.315 0)
			(layer "F.Fab")
			(hide yes)
			(effects
				(font
					(size 1 1)
					(thickness 0.15)
				)
			)
		)
		(sheetfile "environment-sensor.kicad_sch")
		(attr smd)
		(fp_rect
			(start -0.925 -0.47)
			(end 0.925 0.47)
			(stroke
				(width 0.05)
				(type default)
			)
			(fill no)
			(layer "F.CrtYd")
		)
		(fp_line
			(start 0.504 -0.25)
			(end 0.504 0.248)
			(stroke
				(width 0.15)
				(type solid)
			)
			(layer "F.Fab")
		)
		(fp_line
			(start -0.494 -0.25)
			(end 0.504 -0.25)
			(stroke
				(width 0.15)
				(type solid)
			)
			(layer "F.Fab")
		)
		(fp_line
			(start 0.504 0.248)
			(end -0.494 0.248)
			(stroke
				(width 0.15)
				(type solid)
			)
			(layer "F.Fab")
		)
		(fp_line
			(start -0.494 0.248)
			(end -0.494 -0.25)
			(stroke
				(width 0.15)
				(type solid)
			)
			(layer "F.Fab")
		)
		(pad "1" smd roundrect
			(at -0.48 0 90)
			(size 0.59 0.64)
			(layers "F.Cu" "F.Mask" "F.Paste")
			(roundrect_rratio 0.25)
			(net 1 "GND")
			(pintype "passive")
		)
		(pad "2" smd roundrect
			(at 0.48 0 90)
			(size 0.59 0.64)
			(layers "F.Cu" "F.Mask" "F.Paste")
			(roundrect_rratio 0.25)
			(net 2 "+3V3")
			(pintype "passive")
		)
	)
	(footprint "antmicro-footprints:SOD-923"
		(layer "F.Cu")
		(at 168.035 129.55 90)
		(property "Reference" "D2"
			(at 1.15 -0.385 0)
			(unlocked yes)
			(layer "F.SilkS")
			(effects
				(font
					(size 0.65 0.65)
					(thickness 0.15)
				)
			)
		)
		(property "Value" "ESD9X5.0ST5G"
			(at 0 2.4 90)
			(unlocked yes)
			(layer "F.Fab")
			(effects
				(font
					(size 1 1)
					(thickness 0.15)
				)
			)
		)
		(property "Description" "Unidirectional TVS, 30 kV,  SOD-923, 5 V, 65 pF"
			(at 0 0 90)
			(layer "F.Fab")
			(hide yes)
			(effects
				(font
					(size 1.27 1.27)
					(thickness 0.15)
				)
			)
		)
		(property "Author" "Antmicro"
			(at 297.585 -38.485 0)
			(layer "F.Fab")
			(hide yes)
			(effects
				(font
					(size 1 1)
					(thickness 0.15)
				)
			)
		)
		(property "License" "Apache-2.0"
			(at 297.585 -38.485 0)
			(layer "F.Fab")
			(hide yes)
			(effects
				(font
					(size 1 1)
					(thickness 0.15)
				)
			)
		)
		(property "MPN" "ESD9X5.0ST5G"
			(at 297.585 -38.485 0)
			(layer "F.Fab")
			(hide yes)
			(effects
				(font
					(size 1 1)
					(thickness 0.15)
				)
			)
		)
		(property "Manufacturer" "ON Semiconductor"
			(at 297.585 -38.485 0)
			(layer "F.Fab")
			(hide yes)
			(effects
				(font
					(size 1 1)
					(thickness 0.15)
				)
			)
		)
		(property "Public" "False"
			(at 297.585 -38.485 0)
			(layer "F.Fab")
			(hide yes)
			(effects
				(font
					(size 1 1)
					(thickness 0.15)
				)
			)
		)
		(sheetfile "environment-sensor.kicad_sch")
		(attr smd)
		(fp_line
			(start 0.5 -0.4)
			(end 0.5 -0.3)
			(stroke
				(width 0.15)
				(type solid)
			)
			(layer "F.SilkS")
		)
		(fp_line
			(start -0.16 -0.4)
			(end -0.16 0.4)
			(stroke
				(width 0.15)
				(type solid)
			)
			(layer "F.SilkS")
		)
		(fp_line
			(start -0.5 -0.4)
			(end 0.5 -0.4)
			(stroke
				(width 0.15)
				(type solid)
			)
			(layer "F.SilkS")
		)
		(fp_line
			(start -0.5 -0.3)
			(end -0.5 -0.4)
			(stroke
				(width 0.15)
				(type solid)
			)
			(layer "F.SilkS")
		)
		(fp_line
			(start 0.5 0.4)
			(end 0.5 0.3)
			(stroke
				(width 0.15)
				(type solid)
			)
			(layer "F.SilkS")
		)
		(fp_line
			(start -0.5 0.4)
			(end -0.5 0.3)
			(stroke
				(width 0.15)
				(type solid)
			)
			(layer "F.SilkS")
		)
		(fp_line
			(start -0.5 0.4)
			(end 0.5 0.4)
			(stroke
				(width 0.15)
				(type solid)
			)
			(layer "F.SilkS")
		)
		(fp_rect
			(start -0.68 -0.41)
			(end 0.68 0.41)
			(stroke
				(width 0.05)
				(type solid)
			)
			(fill no)
			(layer "F.CrtYd")
		)
		(fp_line
			(start -0.202 -0.3)
			(end -0.202 0.298)
			(stroke
				(width 0.15)
				(type solid)
			)
			(layer "F.Fab")
		)
		(fp_rect
			(start -0.402 -0.3)
			(end 0.4 0.298)
			(stroke
				(width 0.15)
				(type solid)
			)
			(fill no)
			(layer "F.Fab")
		)
		(fp_text user "${REFERENCE}"
			(at 0 1.1 90)
			(unlocked yes)
			(layer "F.Fab")
			(effects
				(font
					(size 1 1)
					(thickness 0.15)
				)
			)
		)
		(pad "1" smd roundrect
			(at -0.438 0 90)
			(size 0.4 0.325)
			(layers "F.Cu" "F.Mask" "F.Paste")
			(roundrect_rratio 0.25)
			(net 1 "GND")
			(pinfunction "C")
			(pintype "passive")
		)
		(pad "2" smd roundrect
			(at 0.436 0 90)
			(size 0.4 0.325)
			(layers "F.Cu" "F.Mask" "F.Paste")
			(roundrect_rratio 0.25)
			(net 27 "/VBUS")
			(pinfunction "A")
			(pintype "passive")
		)
	)
)
